1
2
3
4
55
4
3
2
1
A B C D E F G H
HGFEDCBA
RANGE TOLERANCE
0-10
10-50
50-100
100-
0.10
0.15
0.20
0.25
DRAWN
DESIGNED
APPROVED
1.57
120.4
0
13.38
25.62
77.16
103.93
97.91
94.86 94.86
90
0
29.73
39.42
82
26.75
36.4
39.5
62.7
79.2
6.05
4.69
5.09
2x 6.29
3x 6.29
4.69
8
16.23
22.98
53.63
60.38
70.6
2
1 TBD
ITEM PART NO. DESCRIPTION
REVISIONS
LTR DESCRIPTION DATE APP.
Quanta Computer Inc.
MODEL
TBD
NAME SCM PCBA TBD
TOL. 
1 PLC 2 PLC ANGLE
UNIT mm TBD
MATERIAL TBD SCALE 1:2 TBD
FINISH TBD DATE Nov-12-21REV.
THE 3RD PROJECTION DWG.
NO. TBD 1/3
DWG NAME F0T-2OU-SCM-PCBA
SCALE 1:1



1
2
3
4
55
4
3
2
1
A B C D E F G H
HGFEDCBA
RANGE TOLERANCE
0-10
10-50
50-100
100-
0.10
0.15
0.20
0.25
DRAWN
DESIGNED
APPROVED
2X 3.4
2X 6
2X 3.13
2X 6.03
3.2
3.8
4.5
8
3.8
6.4
6
1.6
3.2
6.4
6
1.6
2X 3.2
2X 6.5
5.6
0
6.1
83.9
84.7
60
76.5
26.75
54.19
0
120.4
2x 11.79
2x 22.69
2x 107.7
DWG NAME F0T-2OU-SCM-PCBA
2
1 TBD
ITEM PART NO. DESCRIPTION
REVISIONS
LTR DESCRIPTION DATE APP.
Quanta Computer Inc.
MODEL
TBD
NAME SCM PCBA TBD
TOL. 
1 PLC 2 PLC ANGLE
UNIT mm TBD
MATERIAL TBD SCALE 1:2 TBD
FINISH TBD DATE Nov-17-21REV.
THE 3RD PROJECTION DWG.
NO. TBD 2/3
SCALE 1:1
SEE DETAIL A
SEE DETAIL B
SEE DETAIL C
SEE DETAIL E
DETAIL A
SCALE 2:1
HOLE620
DETAIL B
SCALE 2:1
HOLE1211
DETAIL C
SCALE 2:1
HOLE_C6-5D3-2
SEE DETAIL F
DETAIL E
SCALE 2:1 HOLE1247
HOLE1248
DETAIL F
SCALE 2:1



1
2
3
4
55
4
3
2
1
A B C D E F G H
HGFEDCBA
RANGE TOLERANCE
0-10
10-50
50-100
100-
0.10
0.15
0.20
0.25
DRAWN
DESIGNED
APPROVED
120.4
90
1.57 0.15
8X 30 0.5
2
1 TBD
ITEM PART NO. DESCRIPTION
REVISIONS
LTR DESCRIPTION DATE APP.
Quanta Computer Inc.
MODEL
TBD
NAME SCM PCBA TBD
TOL. 
1 PLC 2 PLC ANGLE
UNIT mm TBD
MATERIAL TBD SCALE 1:2 TBD
FINISH TBD DATE Nov-17-21REV.
THE 3RD PROJECTION DWG.
NO. TBD 3/3
DWG NAME F0T-2OU-SCM-PCBA
SEE DETAIL D
DETAIL D
SCALE 2:1